(kicad_pcb
	(version 20260206)
	(generator "pcbnew")
	(generator_version "10.0")
	(general
		(thickness 1.6)
		(legacy_teardrops no)
	)
	(paper "A4")
	(title_block
		(title "9054_F0T_PDB_BD_GPU_F_V04_1213_1550_OCP.brd")
		(comment 1 "Grand Teton / footprints 179-182 of 608")
	)
	(layers
		(0 "F.Cu" signal "TOP")
		(4 "In1.Cu" signal "GND")
		(6 "In2.Cu" signal "IN1")
		(8 "In3.Cu" signal "GND1")
		(10 "In4.Cu" signal "VCC")
		(12 "In5.Cu" signal "VCC1")
		(14 "In6.Cu" signal "GND2")
		(16 "In7.Cu" signal "IN2")
		(18 "In8.Cu" signal "GND3")
		(2 "B.Cu" signal "BOTTOM")
		(9 "F.Adhes" user "F.Adhesive")
		(11 "B.Adhes" user "B.Adhesive")
		(13 "F.Paste" user "Package Geometry/Pastemask Top")
		(15 "B.Paste" user "Package Geometry/Pastemask Bottom")
		(5 "F.SilkS" user "Ref Des/Silkscreen Top")
		(7 "B.SilkS" user "Ref Des/Silkscreen Bottom")
		(1 "F.Mask" user "Board Geometry/Soldermask Top")
		(3 "B.Mask" user "Board Geometry/Soldermask Bottom")
		(17 "Dwgs.User" user "User.Drawings")
		(19 "Cmts.User" user "User.Comments")
		(21 "Eco1.User" user "User.Eco1")
		(23 "Eco2.User" user "User.Eco2")
		(25 "Edge.Cuts" user "Board Geometry/Outline")
		(27 "Margin" user)
		(31 "F.CrtYd" user "Package Geometry/Place Bound Top")
		(29 "B.CrtYd" user "Package Geometry/Place Bound Bottom")
		(35 "F.Fab" user "Ref Des/Assembly Top")
		(33 "B.Fab" user "Ref Des/Assembly Bottom")
	)
	(footprint ""
		(layer "F.Cu")
		(at 436.9054 -50.419 180)
		(property "Reference" "U33"
			(at 1.7399 2.37363 0)
			(unlocked yes)
			(layer "F.SilkS")
			(effects
				(font
					(size 0.7874 0.5842)
					(thickness 0.1524)
				)
				(justify left)
			)
		)
		(property "Value" ""
			(at 0 0 180)
			(layer "F.Fab")
			(effects
				(font
					(size 1.27 1.27)
				)
			)
		)
		(duplicate_pad_numbers_are_jumpers no)
		(fp_line
			(start 1.733296 1.549908)
			(end 1.733296 -1.549908)
			(stroke
				(width 0.1524)
				(type default)
			)
			(layer "F.SilkS")
		)
		(fp_line
			(start 1.733296 -1.549908)
			(end 0.660908 -1.549908)
			(stroke
				(width 0.1524)
				(type default)
			)
			(layer "F.SilkS")
		)
		(fp_line
			(start 0.660908 -1.549908)
			(end 0 -0.889)
			(stroke
				(width 0.1524)
				(type default)
			)
			(layer "F.SilkS")
		)
		(fp_line
			(start 0 -0.889)
			(end -0.660908 -1.549908)
			(stroke
				(width 0.1524)
				(type default)
			)
			(layer "F.SilkS")
		)
		(fp_line
			(start -0.660908 -1.549908)
			(end -1.733296 -1.549908)
			(stroke
				(width 0.1524)
				(type default)
			)
			(layer "F.SilkS")
		)
		(fp_line
			(start -1.733296 1.549908)
			(end 1.733296 1.549908)
			(stroke
				(width 0.1524)
				(type default)
			)
			(layer "F.SilkS")
		)
		(fp_line
			(start -1.733296 -1.549908)
			(end -1.733296 1.549908)
			(stroke
				(width 0.1524)
				(type default)
			)
			(layer "F.SilkS")
		)
		(fp_poly
			(pts
				(xy -0.9906 -2.159) (xy -1.4986 -2.159) (xy -1.2446 -1.651)
			)
			(stroke
				(width 0)
				(type default)
			)
			(fill yes)
			(layer "F.SilkS")
		)
		(fp_line
			(start 0.849884 1.549908)
			(end 0.849884 -1.549908)
			(stroke
				(width 0.1)
				(type default)
			)
			(layer "F.Fab")
		)
		(fp_line
			(start 0.849884 -1.549908)
			(end -0.849884 -1.549908)
			(stroke
				(width 0.1)
				(type default)
			)
			(layer "F.Fab")
		)
		(fp_line
			(start -0.849884 1.549908)
			(end 0.849884 1.549908)
			(stroke
				(width 0.1)
				(type default)
			)
			(layer "F.Fab")
		)
		(fp_line
			(start -0.849884 -1.549908)
			(end -0.849884 1.549908)
			(stroke
				(width 0.1)
				(type default)
			)
			(layer "F.Fab")
		)
		(fp_poly
			(pts
				(xy -2.4384 -1.20396) (xy -2.4384 -0.69596) (xy -1.9304 -0.94996)
			)
			(stroke
				(width 0)
				(type default)
			)
			(fill yes)
			(layer "F.Fab")
		)
		(pad "1" smd rect
			(at -1.199896 -0.94996 90)
			(size 0.5588 0.8128)
			(layers "F.Cu" "F.Mask" "F.Paste")
			(net "PWRGD_P52V_HS1_PG")
		)
		(pad "2" smd rect
			(at -1.199896 0 90)
			(size 0.5588 0.8128)
			(layers "F.Cu" "F.Mask" "F.Paste")
			(net "PWRGD_P52V_HS2_PG")
		)
		(pad "3" smd rect
			(at -1.199896 0.94996 90)
			(size 0.5588 0.8128)
			(layers "F.Cu" "F.Mask" "F.Paste")
			(net "GND")
		)
		(pad "4" smd rect
			(at 1.199896 0.94996 90)
			(size 0.5588 0.8128)
			(layers "F.Cu" "F.Mask" "F.Paste")
			(net "PWRGD_P52V_HS_PG_R2")
		)
		(pad "5" smd rect
			(at 1.199896 -0.94996 90)
			(size 0.5588 0.8128)
			(layers "F.Cu" "F.Mask" "F.Paste")
			(net "P3V3_AUX")
		)
	)
	(footprint ""
		(layer "F.Cu")
		(at 302.4124 -36.1442)
		(property "Reference" "PR6964"
			(at 0 0 0)
			(layer "F.SilkS")
			(hide yes)
			(effects
				(font
					(size 1.27 1.27)
				)
			)
		)
		(property "Value" ""
			(at 0 0 0)
			(layer "F.Fab")
			(effects
				(font
					(size 1.27 1.27)
				)
			)
		)
		(duplicate_pad_numbers_are_jumpers no)
		(fp_line
			(start -1.2954 -0.5842)
			(end 1.2954 -0.5842)
			(stroke
				(width 0.1524)
				(type default)
			)
			(layer "F.SilkS")
		)
		(fp_line
			(start -1.2954 0.5842)
			(end -1.2954 -0.5842)
			(stroke
				(width 0.1524)
				(type default)
			)
			(layer "F.SilkS")
		)
		(fp_line
			(start 1.2954 -0.5842)
			(end 1.2954 0.5842)
			(stroke
				(width 0.1524)
				(type default)
			)
			(layer "F.SilkS")
		)
		(fp_line
			(start 1.2954 0.5842)
			(end -1.2954 0.5842)
			(stroke
				(width 0.1524)
				(type default)
			)
			(layer "F.SilkS")
		)
		(fp_line
			(start -1.1938 -0.406654)
			(end -0.8636 -0.406654)
			(stroke
				(width 0.1)
				(type default)
			)
			(layer "F.Fab")
		)
		(fp_line
			(start -1.1938 0.4064)
			(end -1.1938 -0.406654)
			(stroke
				(width 0.1)
				(type default)
			)
			(layer "F.Fab")
		)
		(fp_line
			(start -0.8636 -0.4572)
			(end 0.8636 -0.4572)
			(stroke
				(width 0.1)
				(type default)
			)
			(layer "F.Fab")
		)
		(fp_line
			(start -0.8636 -0.406654)
			(end -0.8636 -0.4572)
			(stroke
				(width 0.1)
				(type default)
			)
			(layer "F.Fab")
		)
		(fp_line
			(start -0.8636 0.4064)
			(end -1.1938 0.4064)
			(stroke
				(width 0.1)
				(type default)
			)
			(layer "F.Fab")
		)
		(fp_line
			(start -0.8636 0.4318)
			(end -0.8636 0.4064)
			(stroke
				(width 0.1)
				(type default)
			)
			(layer "F.Fab")
		)
		(fp_line
			(start -0.8636 0.4572)
			(end -0.8636 0.4318)
			(stroke
				(width 0.1)
				(type default)
			)
			(layer "F.Fab")
		)
		(fp_line
			(start 0.8636 -0.4572)
			(end 0.8636 -0.406654)
			(stroke
				(width 0.1)
				(type default)
			)
			(layer "F.Fab")
		)
		(fp_line
			(start 0.8636 -0.406654)
			(end 1.1938 -0.406654)
			(stroke
				(width 0.1)
				(type default)
			)
			(layer "F.Fab")
		)
		(fp_line
			(start 0.8636 0.4064)
			(end 0.8636 0.4572)
			(stroke
				(width 0.1)
				(type default)
			)
			(layer "F.Fab")
		)
		(fp_line
			(start 0.8636 0.4572)
			(end -0.8636 0.4572)
			(stroke
				(width 0.1)
				(type default)
			)
			(layer "F.Fab")
		)
		(fp_line
			(start 1.1938 -0.406654)
			(end 1.1938 0.4064)
			(stroke
				(width 0.1)
				(type default)
			)
			(layer "F.Fab")
		)
		(fp_line
			(start 1.1938 0.4064)
			(end 0.8636 0.4064)
			(stroke
				(width 0.1)
				(type default)
			)
			(layer "F.Fab")
		)
		(pad "1" smd rect
			(at -0.7366 0 270)
			(size 0.7112 0.8128)
			(layers "F.Cu" "F.Mask" "F.Paste")
			(net "P52V_HS1_SENSE_P_R2")
		)
		(pad "2" smd rect
			(at 0.7366 0 270)
			(size 0.7112 0.8128)
			(layers "F.Cu" "F.Mask" "F.Paste")
			(net "P52V_HS_4287_ADC_P")
		)
	)
	(footprint ""
		(layer "F.Cu")
		(at 281.0764 -72.39)
		(property "Reference" "R374"
			(at 0 0 0)
			(layer "F.SilkS")
			(hide yes)
			(effects
				(font
					(size 1.27 1.27)
				)
			)
		)
		(property "Value" ""
			(at 0 0 0)
			(layer "F.Fab")
			(effects
				(font
					(size 1.27 1.27)
				)
			)
		)
		(duplicate_pad_numbers_are_jumpers no)
		(fp_line
			(start -0.7874 -0.4064)
			(end 0.7874 -0.4064)
			(stroke
				(width 0.1524)
				(type default)
			)
			(layer "F.SilkS")
		)
		(fp_line
			(start -0.7874 0.4064)
			(end -0.7874 -0.4064)
			(stroke
				(width 0.1524)
				(type default)
			)
			(layer "F.SilkS")
		)
		(fp_line
			(start 0.7874 -0.4064)
			(end 0.7874 0.4064)
			(stroke
				(width 0.1524)
				(type default)
			)
			(layer "F.SilkS")
		)
		(fp_line
			(start 0.7874 0.4064)
			(end -0.7874 0.4064)
			(stroke
				(width 0.1524)
				(type default)
			)
			(layer "F.SilkS")
		)
		(fp_line
			(start -0.67945 -0.305054)
			(end -0.12065 -0.305054)
			(stroke
				(width 0.1)
				(type default)
			)
			(layer "F.Fab")
		)
		(fp_line
			(start -0.67945 0.3048)
			(end -0.67945 -0.305054)
			(stroke
				(width 0.1)
				(type default)
			)
			(layer "F.Fab")
		)
		(fp_line
			(start -0.12065 -0.305054)
			(end -0.12065 -0.2794)
			(stroke
				(width 0.1)
				(type default)
			)
			(layer "F.Fab")
		)
		(fp_line
			(start -0.12065 -0.2794)
			(end 0.12065 -0.2794)
			(stroke
				(width 0.1)
				(type default)
			)
			(layer "F.Fab")
		)
		(fp_line
			(start -0.12065 0.2794)
			(end -0.12065 0.3048)
			(stroke
				(width 0.1)
				(type default)
			)
			(layer "F.Fab")
		)
		(fp_line
			(start -0.12065 0.3048)
			(end -0.67945 0.3048)
			(stroke
				(width 0.1)
				(type default)
			)
			(layer "F.Fab")
		)
		(fp_line
			(start 0.120396 0.2794)
			(end -0.12065 0.2794)
			(stroke
				(width 0.1)
				(type default)
			)
			(layer "F.Fab")
		)
		(fp_line
			(start 0.120396 0.3048)
			(end 0.120396 0.2794)
			(stroke
				(width 0.1)
				(type default)
			)
			(layer "F.Fab")
		)
		(fp_line
			(start 0.12065 -0.3048)
			(end 0.67945 -0.3048)
			(stroke
				(width 0.1)
				(type default)
			)
			(layer "F.Fab")
		)
		(fp_line
			(start 0.12065 -0.2794)
			(end 0.12065 -0.3048)
			(stroke
				(width 0.1)
				(type default)
			)
			(layer "F.Fab")
		)
		(fp_line
			(start 0.67945 -0.3048)
			(end 0.67945 0.3048)
			(stroke
				(width 0.1)
				(type default)
			)
			(layer "F.Fab")
		)
		(fp_line
			(start 0.67945 0.3048)
			(end 0.120396 0.3048)
			(stroke
				(width 0.1)
				(type default)
			)
			(layer "F.Fab")
		)
		(pad "1" smd circle
			(at -0.40005 0)
			(size 0 0)
			(layers "F.Cu" "F.Mask" "F.Paste")
			(net "P52V_HS1_ADR1")
		)
		(pad "2" smd circle
			(at 0.40005 0)
			(size 0 0)
			(layers "F.Cu" "F.Mask" "F.Paste")
			(net "GND_FIELD_SIGNAL")
		)
	)
	(footprint ""
		(layer "F.Cu")
		(at 417.5506 -28.7528 -90)
		(property "Reference" "U38"
			(at -1.7907 -4.25577 90)
			(unlocked yes)
			(layer "F.SilkS")
			(effects
				(font
					(size 0.7874 0.5842)
					(thickness 0.1524)
				)
				(justify left)
			)
		)
		(property "Value" ""
			(at 0 0 270)
			(layer "F.Fab")
			(effects
				(font
					(size 1.27 1.27)
				)
			)
		)
		(duplicate_pad_numbers_are_jumpers no)
		(fp_line
			(start -1.549908 2.549906)
			(end -0.753872 2.549906)
			(stroke
				(width 0.1524)
				(type default)
			)
			(layer "F.SilkS")
		)
		(fp_line
			(start -0.245872 2.549906)
			(end 0.245872 2.549906)
			(stroke
				(width 0.1524)
				(type default)
			)
			(layer "F.SilkS")
		)
		(fp_line
			(start 0.753872 2.549906)
			(end 1.549908 2.549906)
			(stroke
				(width 0.1524)
				(type default)
			)
			(layer "F.SilkS")
		)
		(fp_line
			(start 1.549908 2.549906)
			(end 1.549908 2.253996)
			(stroke
				(width 0.1524)
				(type default)
			)
			(layer "F.SilkS")
		)
		(fp_line
			(start -1.549908 2.253996)
			(end -1.549908 2.549906)
			(stroke
				(width 0.1524)
				(type default)
			)
			(layer "F.SilkS")
		)
		(fp_line
			(start 1.549908 -2.253996)
			(end 1.549908 -2.549906)
			(stroke
				(width 0.1524)
				(type default)
			)
			(layer "F.SilkS")
		)
		(fp_line
			(start -1.549908 -2.549906)
			(end -1.549908 -2.251964)
			(stroke
				(width 0.1524)
				(type default)
			)
			(layer "F.SilkS")
		)
		(fp_line
			(start -0.752094 -2.549906)
			(end -1.549908 -2.549906)
			(stroke
				(width 0.1524)
				(type default)
			)
			(layer "F.SilkS")
		)
		(fp_line
			(start 0.2413 -2.549906)
			(end -0.2413 -2.549906)
			(stroke
				(width 0.1524)
				(type default)
			)
			(layer "F.SilkS")
		)
		(fp_line
			(start 1.549908 -2.549906)
			(end 0.752094 -2.549906)
			(stroke
				(width 0.1524)
				(type default)
			)
			(layer "F.SilkS")
		)
		(fp_poly
			(pts
				(xy -2.06121 -2.13741) (xy -2.964434 -2.438654) (xy -2.362454 -3.040634)
			)
			(stroke
				(width 0)
				(type default)
			)
			(fill yes)
			(layer "F.SilkS")
		)
		(fp_line
			(start -1.549908 2.549906)
			(end 1.549908 2.549906)
			(stroke
				(width 0.1)
				(type default)
			)
			(layer "F.Fab")
		)
		(fp_line
			(start 1.549908 2.549906)
			(end 1.549908 -2.549906)
			(stroke
				(width 0.1)
				(type default)
			)
			(layer "F.Fab")
		)
		(fp_line
			(start -1.549908 -2.549906)
			(end -1.549908 2.549906)
			(stroke
				(width 0.1)
				(type default)
			)
			(layer "F.Fab")
		)
		(fp_line
			(start 1.549908 -2.549906)
			(end -1.549908 -2.549906)
			(stroke
				(width 0.1)
				(type default)
			)
			(layer "F.Fab")
		)
		(fp_poly
			(pts
				(xy -1.891538 -1.999996) (xy -2.7432 -1.574292) (xy -2.7432 -2.4257)
			)
			(stroke
				(width 0)
				(type default)
			)
			(fill yes)
			(layer "F.Fab")
		)
		(fp_text user "11"
			(at 2.2606 5.87375 270)
			(unlocked yes)
			(layer "F.SilkS")
			(effects
				(font
					(size 0.635 0.4064)
					(thickness 0.1524)
				)
			)
		)
		(fp_text user "10"
			(at -1.4224 3.253232 270)
			(unlocked yes)
			(layer "F.SilkS")
			(effects
				(font
					(size 0.635 0.4064)
					(thickness 0.1524)
				)
			)
		)
		(fp_text user "9"
			(at -2.338832 2.5908 180)
			(unlocked yes)
			(layer "F.SilkS")
			(effects
				(font
					(size 0.635 0.4064)
					(thickness 0.1524)
				)
			)
		)
		(fp_text user "12"
			(at 3.67665 1.143 180)
			(unlocked yes)
			(layer "F.SilkS")
			(effects
				(font
					(size 0.635 0.4064)
					(thickness 0.1524)
				)
			)
		)
		(fp_text user "20"
			(at 1.79705 -3.2004 180)
			(unlocked yes)
			(layer "F.SilkS")
			(effects
				(font
					(size 0.635 0.4064)
					(thickness 0.1524)
				)
			)
		)
		(fp_text user "21_22"
			(at -0.0762 -3.401568 270)
			(unlocked yes)
			(layer "F.SilkS")
			(effects
				(font
					(size 0.635 0.4064)
					(thickness 0.1524)
				)
			)
		)
		(fp_text user "11"
			(at 1.1938 3.329432 270)
			(unlocked yes)
			(layer "F.Fab")
			(effects
				(font
					(size 0.635 0.4064)
					(thickness 0.1524)
				)
			)
		)
		(fp_text user "10"
			(at -1.4224 3.253232 270)
			(unlocked yes)
			(layer "F.Fab")
			(effects
				(font
					(size 0.635 0.4064)
					(thickness 0.1524)
				)
			)
		)
		(fp_text user "12"
			(at 2.207768 2.7178 180)
			(unlocked yes)
			(layer "F.Fab")
			(effects
				(font
					(size 0.635 0.4064)
					(thickness 0.1524)
				)
			)
		)
		(fp_text user "9"
			(at -2.338832 2.5908 180)
			(unlocked yes)
			(layer "F.Fab")
			(effects
				(font
					(size 0.635 0.4064)
					(thickness 0.1524)
				)
			)
		)
		(fp_text user "20"
			(at 2.055368 -2.7686 180)
			(unlocked yes)
			(layer "F.Fab")
			(effects
				(font
					(size 0.635 0.4064)
					(thickness 0.1524)
				)
			)
		)
		(fp_text user "21_22"
			(at -0.0762 -3.401568 270)
			(unlocked yes)
			(layer "F.Fab")
			(effects
				(font
					(size 0.635 0.4064)
					(thickness 0.1524)
				)
			)
		)
		(pad "1" smd circle
			(at -1.374902 -1.999996 180)
			(size 0 0)
			(layers "F.Cu" "F.Mask" "F.Paste")
			(net "P12V_LED_EN_R")
		)
		(pad "2" smd rect
			(at -1.400048 -1.500124 180)
			(size 0.254 0.8128)
			(layers "F.Cu" "F.Mask" "F.Paste")
			(net "GND")
		)
		(pad "3" smd rect
			(at -1.400048 -0.999998 180)
			(size 0.254 0.8128)
			(layers "F.Cu" "F.Mask" "F.Paste")
			(net "GND")
		)
		(pad "4" smd rect
			(at -1.400048 -0.499872 180)
			(size 0.254 0.8128)
			(layers "F.Cu" "F.Mask" "F.Paste")
			(net "P12V_LED_TIMER")
		)
		(pad "5" smd rect
			(at -1.400048 0 180)
			(size 0.254 0.8128)
			(layers "F.Cu" "F.Mask" "F.Paste")
			(net "P12V_LED_ISET")
		)
		(pad "6" smd rect
			(at -1.400048 0.499872 180)
			(size 0.254 0.8128)
			(layers "F.Cu" "F.Mask" "F.Paste")
			(net "P12V_LED_SS")
		)
		(pad "7" smd rect
			(at -1.400048 0.999998 180)
			(size 0.254 0.8128)
			(layers "F.Cu" "F.Mask" "F.Paste")
			(net "GND")
		)
		(pad "8" smd rect
			(at -1.400048 1.500124 180)
			(size 0.254 0.8128)
			(layers "F.Cu" "F.Mask" "F.Paste")
			(net "P12V_LED_IMON")
		)
		(pad "9" smd rect
			(at -1.400048 1.999996 180)
			(size 0.254 0.8128)
			(layers "F.Cu" "F.Mask" "F.Paste")
			(net "P12V_LED_FLTB")
		)
		(pad "10" smd rect
			(at -0.499872 2.400046 270)
			(size 0.254 0.8128)
			(layers "F.Cu" "F.Mask" "F.Paste")
			(net "PWRGD_P12V_FAN_LED_R")
		)
		(pad "11" smd rect
			(at 0.499872 2.400046 270)
			(size 0.254 0.8128)
			(layers "F.Cu" "F.Mask" "F.Paste")
			(net "P12V_LED_FB")
		)
		(pad "12" smd rect
			(at 1.400048 1.999996 180)
			(size 0.254 0.8128)
			(layers "F.Cu" "F.Mask" "F.Paste")
			(net "P12V_LED_PD")
		)
		(pad "13" smd rect
			(at 1.400048 1.500124 180)
			(size 0.254 0.8128)
			(layers "F.Cu" "F.Mask" "F.Paste")
			(net "P12V_FAN_LED")
		)
		(pad "14" smd rect
			(at 1.400048 0.999998 180)
			(size 0.254 0.8128)
			(layers "F.Cu" "F.Mask" "F.Paste")
			(net "P12V_FAN_LED")
		)
		(pad "15" smd rect
			(at 1.400048 0.499872 180)
			(size 0.254 0.8128)
			(layers "F.Cu" "F.Mask" "F.Paste")
			(net "P12V_FAN_LED")
		)
		(pad "16" smd rect
			(at 1.400048 0 180)
			(size 0.254 0.8128)
			(layers "F.Cu" "F.Mask" "F.Paste")
			(net "P12V_FAN_LED")
		)
		(pad "17" smd rect
			(at 1.400048 -0.499872 180)
			(size 0.254 0.8128)
			(layers "F.Cu" "F.Mask" "F.Paste")
			(net "P12V_FAN_LED")
		)
		(pad "18" smd rect
			(at 1.400048 -0.999998 180)
			(size 0.254 0.8128)
			(layers "F.Cu" "F.Mask" "F.Paste")
			(net "P12V_FAN_LED")
		)
		(pad "19" smd rect
			(at 1.400048 -1.500124 180)
			(size 0.254 0.8128)
			(layers "F.Cu" "F.Mask" "F.Paste")
			(net "P12V_FAN_LED")
		)
		(pad "20" smd rect
			(at 1.400048 -1.999996 180)
			(size 0.254 0.8128)
			(layers "F.Cu" "F.Mask" "F.Paste")
			(net "P12V_FAN_LED")
		)
		(pad "21_22" smd circle
			(at 0.499872 -2.337562 180)
			(size 0 0)
			(layers "F.Cu" "F.Mask" "F.Paste")
			(net "P12V_HPDB")
		)
		(pad "23" smd rect
			(at 0 -1.100074 180)
			(size 0.254 1.27)
			(layers "F.Cu" "F.Mask" "F.Paste")
			(net "P12V_HPDB")
		)
		(pad "24" smd rect
			(at 0 -0.199898 180)
			(size 0.254 1.27)
			(layers "F.Cu" "F.Mask" "F.Paste")
			(net "P12V_HPDB")
		)
		(pad "25" smd rect
			(at 0 0.700024 180)
			(size 0.254 1.27)
			(layers "F.Cu" "F.Mask" "F.Paste")
			(net "P12V_HPDB")
		)
		(pad "26" smd rect
			(at 0 1.599946 180)
			(size 0.254 1.27)
			(layers "F.Cu" "F.Mask" "F.Paste")
			(net "P12V_HPDB")
		)
	)
)
